# S9S_MB_2U (Grand Teton) — schematic netlist excerpt (pin names and nets, part order shuffled) for the footprints in the layout excerpt that follows; sources: Cadence DE-HDL packaged netlist, KiCad conversion of 03242023_DA0F0TMBIJ0_F0T_Motherboard_J_brd_V01_OCP.brd

R4163  Q_RES  100K 1% EMPTY  pkg 0402LF  page 145 : A = GPU_3V3IO_RSVD3 ; B = GND
R803  Q_RES  33.2 1% CHIP  pkg 0402LF  page 221 : A = JTAG_PLD_TDI_R ; B = JTAG_BMC_PLD_TDI

(kicad_pcb
	(version 20260206)
	(generator "pcbnew")
	(generator_version "10.0")
	(general
		(thickness 1.6)
		(legacy_teardrops no)
	)
	(paper "A4")
	(title_block
		(title "03242023_DA0F0TMBIJ0_F0T_Motherboard_J_brd_V01_OCP.brd")
		(comment 1 "Grand Teton / footprints 746-747 of 6105")
	)
	(layers
		(0 "F.Cu" signal "TOP")
		(4 "In1.Cu" signal "GND")
		(6 "In2.Cu" signal "IN1")
		(8 "In3.Cu" signal "GND1")
		(10 "In4.Cu" signal "IN2")
		(12 "In5.Cu" signal "GND2")
		(14 "In6.Cu" signal "IN3")
		(16 "In7.Cu" signal "GND3")
		(18 "In8.Cu" signal "VCC")
		(20 "In9.Cu" signal "VCC1")
		(22 "In10.Cu" signal "GND4")
		(24 "In11.Cu" signal "IN4")
		(26 "In12.Cu" signal "GND5")
		(28 "In13.Cu" signal "IN5")
		(30 "In14.Cu" signal "GND6")
		(32 "In15.Cu" signal "IN6")
		(34 "In16.Cu" signal "GND7")
		(2 "B.Cu" signal "BOTTOM")
		(9 "F.Adhes" user "F.Adhesive")
		(11 "B.Adhes" user "B.Adhesive")
		(13 "F.Paste" user "Package Geometry/Pastemask Top")
		(15 "B.Paste" user "Package Geometry/Pastemask Bottom")
		(5 "F.SilkS" user "Ref Des/Silkscreen Top")
		(7 "B.SilkS" user "Ref Des/Silkscreen Bottom")
		(1 "F.Mask" user "Board Geometry/Soldermask Top")
		(3 "B.Mask" user "Board Geometry/Soldermask Bottom")
		(17 "Dwgs.User" user "User.Drawings")
		(19 "Cmts.User" user "User.Comments")
		(21 "Eco1.User" user "User.Eco1")
		(23 "Eco2.User" user "User.Eco2")
		(25 "Edge.Cuts" user "Board Geometry/Outline")
		(27 "Margin" user)
		(31 "F.CrtYd" user "Package Geometry/Place Bound Top")
		(29 "B.CrtYd" user "Package Geometry/Place Bound Bottom")
		(35 "F.Fab" user "Ref Des/Assembly Top")
		(33 "B.Fab" user "Ref Des/Assembly Bottom")
	)
	(footprint ""
		(layer "F.Cu")
		(at 357.548942 -390.43737 180)
		(property "Reference" "R4163"
			(at 0 0 180)
			(layer "F.SilkS")
			(hide yes)
			(effects
				(font
					(size 1.27 1.27)
				)
			)
		)
		(property "Value" ""
			(at 0 0 180)
			(layer "F.Fab")
			(effects
				(font
					(size 1.27 1.27)
				)
			)
		)
		(duplicate_pad_numbers_are_jumpers no)
		(fp_line
			(start 0.7874 0.4064)
			(end -0.7874 0.4064)
			(stroke
				(width 0.1524)
				(type default)
			)
			(layer "F.SilkS")
		)
		(fp_line
			(start 0.7874 -0.4064)
			(end 0.7874 0.4064)
			(stroke
				(width 0.1524)
				(type default)
			)
			(layer "F.SilkS")
		)
		(fp_line
			(start -0.7874 0.4064)
			(end -0.7874 -0.4064)
			(stroke
				(width 0.1524)
				(type default)
			)
			(layer "F.SilkS")
		)
		(fp_line
			(start -0.7874 -0.4064)
			(end 0.7874 -0.4064)
			(stroke
				(width 0.1524)
				(type default)
			)
			(layer "F.SilkS")
		)
		(fp_line
			(start 0.67945 0.3048)
			(end 0.120396 0.3048)
			(stroke
				(width 0.1)
				(type default)
			)
			(layer "F.Fab")
		)
		(fp_line
			(start 0.67945 -0.3048)
			(end 0.67945 0.3048)
			(stroke
				(width 0.1)
				(type default)
			)
			(layer "F.Fab")
		)
		(fp_line
			(start 0.12065 -0.2794)
			(end 0.12065 -0.3048)
			(stroke
				(width 0.1)
				(type default)
			)
			(layer "F.Fab")
		)
		(fp_line
			(start 0.12065 -0.3048)
			(end 0.67945 -0.3048)
			(stroke
				(width 0.1)
				(type default)
			)
			(layer "F.Fab")
		)
		(fp_line
			(start 0.120396 0.3048)
			(end 0.120396 0.2794)
			(stroke
				(width 0.1)
				(type default)
			)
			(layer "F.Fab")
		)
		(fp_line
			(start 0.120396 0.2794)
			(end -0.12065 0.2794)
			(stroke
				(width 0.1)
				(type default)
			)
			(layer "F.Fab")
		)
		(fp_line
			(start -0.12065 0.3048)
			(end -0.67945 0.3048)
			(stroke
				(width 0.1)
				(type default)
			)
			(layer "F.Fab")
		)
		(fp_line
			(start -0.12065 0.2794)
			(end -0.12065 0.3048)
			(stroke
				(width 0.1)
				(type default)
			)
			(layer "F.Fab")
		)
		(fp_line
			(start -0.12065 -0.2794)
			(end 0.12065 -0.2794)
			(stroke
				(width 0.1)
				(type default)
			)
			(layer "F.Fab")
		)
		(fp_line
			(start -0.12065 -0.305054)
			(end -0.12065 -0.2794)
			(stroke
				(width 0.1)
				(type default)
			)
			(layer "F.Fab")
		)
		(fp_line
			(start -0.67945 0.3048)
			(end -0.67945 -0.305054)
			(stroke
				(width 0.1)
				(type default)
			)
			(layer "F.Fab")
		)
		(fp_line
			(start -0.67945 -0.305054)
			(end -0.12065 -0.305054)
			(stroke
				(width 0.1)
				(type default)
			)
			(layer "F.Fab")
		)
		(pad "1" smd circle
			(at -0.40005 0 180)
			(size 0 0)
			(layers "F.Cu" "F.Mask" "F.Paste")
			(net "GPU_3V3IO_RSVD3")
		)
		(pad "2" smd circle
			(at 0.40005 0 180)
			(size 0 0)
			(layers "F.Cu" "F.Mask" "F.Paste")
			(net "GND")
		)
	)
	(footprint ""
		(layer "F.Cu")
		(at 125.205744 -66.867278 90)
		(property "Reference" "R803"
			(at 0 0 90)
			(layer "F.SilkS")
			(hide yes)
			(effects
				(font
					(size 1.27 1.27)
				)
			)
		)
		(property "Value" ""
			(at 0 0 90)
			(layer "F.Fab")
			(effects
				(font
					(size 1.27 1.27)
				)
			)
		)
		(duplicate_pad_numbers_are_jumpers no)
		(fp_line
			(start 0.7874 -0.4064)
			(end 0.7874 0.4064)
			(stroke
				(width 0.1524)
				(type default)
			)
			(layer "F.SilkS")
		)
		(fp_line
			(start -0.7874 -0.4064)
			(end 0.7874 -0.4064)
			(stroke
				(width 0.1524)
				(type default)
			)
			(layer "F.SilkS")
		)
		(fp_line
			(start 0.7874 0.4064)
			(end -0.7874 0.4064)
			(stroke
				(width 0.1524)
				(type default)
			)
			(layer "F.SilkS")
		)
		(fp_line
			(start -0.7874 0.4064)
			(end -0.7874 -0.4064)
			(stroke
				(width 0.1524)
				(type default)
			)
			(layer "F.SilkS")
		)
		(fp_line
			(start -0.12065 -0.305054)
			(end -0.12065 -0.2794)
			(stroke
				(width 0.1)
				(type default)
			)
			(layer "F.Fab")
		)
		(fp_line
			(start -0.67945 -0.305054)
			(end -0.12065 -0.305054)
			(stroke
				(width 0.1)
				(type default)
			)
			(layer "F.Fab")
		)
		(fp_line
			(start 0.67945 -0.3048)
			(end 0.67945 0.3048)
			(stroke
				(width 0.1)
				(type default)
			)
			(layer "F.Fab")
		)
		(fp_line
			(start 0.12065 -0.3048)
			(end 0.67945 -0.3048)
			(stroke
				(width 0.1)
				(type default)
			)
			(layer "F.Fab")
		)
		(fp_line
			(start 0.12065 -0.2794)
			(end 0.12065 -0.3048)
			(stroke
				(width 0.1)
				(type default)
			)
			(layer "F.Fab")
		)
		(fp_line
			(start -0.12065 -0.2794)
			(end 0.12065 -0.2794)
			(stroke
				(width 0.1)
				(type default)
			)
			(layer "F.Fab")
		)
		(fp_line
			(start 0.120396 0.2794)
			(end -0.12065 0.2794)
			(stroke
				(width 0.1)
				(type default)
			)
			(layer "F.Fab")
		)
		(fp_line
			(start -0.12065 0.2794)
			(end -0.12065 0.3048)
			(stroke
				(width 0.1)
				(type default)
			)
			(layer "F.Fab")
		)
		(fp_line
			(start 0.67945 0.3048)
			(end 0.120396 0.3048)
			(stroke
				(width 0.1)
				(type default)
			)
			(layer "F.Fab")
		)
		(fp_line
			(start 0.120396 0.3048)
			(end 0.120396 0.2794)
			(stroke
				(width 0.1)
				(type default)
			)
			(layer "F.Fab")
		)
		(fp_line
			(start -0.12065 0.3048)
			(end -0.67945 0.3048)
			(stroke
				(width 0.1)
				(type default)
			)
			(layer "F.Fab")
		)
		(fp_line
			(start -0.67945 0.3048)
			(end -0.67945 -0.305054)
			(stroke
				(width 0.1)
				(type default)
			)
			(layer "F.Fab")
		)
		(pad "1" smd circle
			(at -0.40005 0 90)
			(size 0 0)
			(layers "F.Cu" "F.Mask" "F.Paste")
			(net "JTAG_PLD_TDI_R")
		)
		(pad "2" smd circle
			(at 0.40005 0 90)
			(size 0 0)
			(layers "F.Cu" "F.Mask" "F.Paste")
			(net "JTAG_BMC_PLD_TDI")
		)
	)
)
